(kicad_pcb
	(version 20260206)
	(generator "pcbnew")
	(generator_version "10.0")
	(general
		(thickness 1.6)
		(legacy_teardrops no)
	)
	(paper "A4")
	(title_block
		(title "Bryce Canyon_IOM_IOC_16318-2_OCP.brd")
		(comment 1 "Bryce Canyon / footprints 1187-1193 of 1605")
	)
	(layers
		(0 "F.Cu" signal "TOP")
		(4 "In1.Cu" signal "L2GND")
		(6 "In2.Cu" signal "L3")
		(8 "In3.Cu" signal "L4VCC")
		(10 "In4.Cu" signal "L5VCC")
		(12 "In5.Cu" signal "L6")
		(14 "In6.Cu" signal "L7GND")
		(2 "B.Cu" signal "BOTTOM")
		(9 "F.Adhes" user "F.Adhesive")
		(11 "B.Adhes" user "B.Adhesive")
		(13 "F.Paste" user "Package Geometry/Pastemask Top")
		(15 "B.Paste" user "Package Geometry/Pastemask Bottom")
		(5 "F.SilkS" user "Ref Des/Silkscreen Top")
		(7 "B.SilkS" user "Ref Des/Silkscreen Bottom")
		(1 "F.Mask" user "Board Geometry/Soldermask Top")
		(3 "B.Mask" user "Board Geometry/Soldermask Bottom")
		(17 "Dwgs.User" user "User.Drawings")
		(19 "Cmts.User" user "User.Comments")
		(21 "Eco1.User" user "User.Eco1")
		(23 "Eco2.User" user "User.Eco2")
		(25 "Edge.Cuts" user "Board Geometry/Outline")
		(27 "Margin" user)
		(31 "F.CrtYd" user "Package Geometry/Place Bound Top")
		(29 "B.CrtYd" user "Package Geometry/Place Bound Bottom")
		(35 "F.Fab" user "Ref Des/Assembly Top")
		(33 "B.Fab" user "Ref Des/Assembly Bottom")
	)
	(footprint ""
		(layer "B.Cu")
		(at 86.3346 -176.8094 -90)
		(property "Reference" "R92"
			(at 0 0 90)
			(layer "B.SilkS")
			(hide yes)
			(effects
				(font
					(size 1.27 1.27)
				)
				(justify mirror)
			)
		)
		(property "Value" "0R2J-2-GP"
			(at -0.064008 -3.993896 270)
			(unlocked yes)
			(layer "B.Fab")
			(hide yes)
			(effects
				(font
					(size 1.016 1.016)
					(thickness 0.1524)
				)
				(justify mirror)
			)
		)
		(property "Device Type" "R402H16"
			(at -0.064008 -5.517896 270)
			(unlocked yes)
			(layer "B.Fab")
			(hide yes)
			(effects
				(font
					(size 1.016 1.016)
					(thickness 0.1524)
				)
				(justify mirror)
			)
		)
		(duplicate_pad_numbers_are_jumpers no)
		(fp_line
			(start -0.508 -0.9398)
			(end 0.508 -0.9398)
			(stroke
				(width 0.1524)
				(type default)
			)
			(layer "B.SilkS")
		)
		(fp_line
			(start 0.508 -0.9398)
			(end 0.508 0.9398)
			(stroke
				(width 0.1524)
				(type default)
			)
			(layer "B.SilkS")
		)
		(fp_rect
			(start 0.508 0.9398)
			(end -0.508 -0.9398)
			(stroke
				(width 0)
				(type default)
			)
			(fill no)
			(layer "B.CrtYd")
		)
		(fp_rect
			(start 0.508 0.9398)
			(end -0.508 -0.9398)
			(stroke
				(width 0)
				(type default)
			)
			(fill no)
			(layer "B.Fab")
		)
		(pad "1" smd custom
			(at 0 -0.4445 90)
			(size 0.1397 0.1397)
			(layers "B.Cu" "B.Mask" "B.Paste")
			(net "I2C_BMC_COMP_SCL_R")
			(options
				(clearance outline)
				(anchor circle)
			)
			(primitives
				(gr_poly
					(pts
						(arc
							(start -0.1778 0.2794)
							(mid -0.249642 0.249642)
							(end -0.2794 0.1778)
						)
						(arc
							(start -0.2794 -0.1778)
							(mid -0.249642 -0.249642)
							(end -0.1778 -0.2794)
						)
						(arc
							(start 0.1778 -0.2794)
							(mid 0.249642 -0.249642)
							(end 0.2794 -0.1778)
						)
						(arc
							(start 0.2794 0.1778)
							(mid 0.249642 0.249642)
							(end 0.1778 0.2794)
						)
					)
					(width 0)
					(fill yes)
				)
			)
		)
		(pad "2" smd custom
			(at 0 0.4445 90)
			(size 0.1397 0.1397)
			(layers "B.Cu" "B.Mask" "B.Paste")
			(net "I2C_BMC_COMP_SCL")
			(options
				(clearance outline)
				(anchor circle)
			)
			(primitives
				(gr_poly
					(pts
						(arc
							(start -0.1778 0.2794)
							(mid -0.249642 0.249642)
							(end -0.2794 0.1778)
						)
						(arc
							(start -0.2794 -0.1778)
							(mid -0.249642 -0.249642)
							(end -0.1778 -0.2794)
						)
						(arc
							(start 0.1778 -0.2794)
							(mid 0.249642 -0.249642)
							(end 0.2794 -0.1778)
						)
						(arc
							(start 0.2794 0.1778)
							(mid 0.249642 0.249642)
							(end 0.1778 0.2794)
						)
					)
					(width 0)
					(fill yes)
				)
			)
		)
	)
	(footprint ""
		(layer "B.Cu")
		(at 40.884856 -182.948072)
		(property "Reference" "C178"
			(at 0 0 0)
			(layer "B.SilkS")
			(hide yes)
			(effects
				(font
					(size 1.27 1.27)
				)
				(justify mirror)
			)
		)
		(property "Value" "SCD1U50V3KX-GP"
			(at 0 -2.8194 0)
			(unlocked yes)
			(layer "B.Fab")
			(hide yes)
			(effects
				(font
					(size 1.016 1.016)
					(thickness 0.1524)
				)
				(justify mirror)
			)
		)
		(property "Device Type" "C603H36"
			(at 0 -4.3434 0)
			(unlocked yes)
			(layer "B.Fab")
			(hide yes)
			(effects
				(font
					(size 1.016 1.016)
					(thickness 0.1524)
				)
				(justify mirror)
			)
		)
		(duplicate_pad_numbers_are_jumpers no)
		(fp_line
			(start -0.508 0)
			(end 0.508 0)
			(stroke
				(width 0.2032)
				(type default)
			)
			(layer "B.SilkS")
		)
		(fp_rect
			(start 0.5842 1.3335)
			(end -0.5842 -1.3335)
			(stroke
				(width 0)
				(type default)
			)
			(fill no)
			(layer "B.CrtYd")
		)
		(fp_rect
			(start 0.5842 1.3335)
			(end -0.5842 -1.3335)
			(stroke
				(width 0)
				(type default)
			)
			(fill no)
			(layer "B.Fab")
		)
		(pad "1" smd custom
			(at 0 -0.762 180)
			(size 0.2159 0.2159)
			(layers "B.Cu" "B.Mask" "B.Paste")
			(net "P3V3_VBST_RC")
			(options
				(clearance outline)
				(anchor circle)
			)
			(primitives
				(gr_poly
					(pts
						(arc
							(start -0.3302 0.4318)
							(mid -0.402042 0.402042)
							(end -0.4318 0.3302)
						)
						(arc
							(start -0.4318 -0.3302)
							(mid -0.402042 -0.402042)
							(end -0.3302 -0.4318)
						)
						(arc
							(start 0.3302 -0.4318)
							(mid 0.402042 -0.402042)
							(end 0.4318 -0.3302)
						)
						(arc
							(start 0.4318 0.3302)
							(mid 0.402042 0.402042)
							(end 0.3302 0.4318)
						)
					)
					(width 0)
					(fill yes)
				)
			)
		)
		(pad "2" smd custom
			(at 0 0.762 180)
			(size 0.2159 0.2159)
			(layers "B.Cu" "B.Mask" "B.Paste")
			(net "P3V3_STBY_LL")
			(options
				(clearance outline)
				(anchor circle)
			)
			(primitives
				(gr_poly
					(pts
						(arc
							(start -0.3302 0.4318)
							(mid -0.402042 0.402042)
							(end -0.4318 0.3302)
						)
						(arc
							(start -0.4318 -0.3302)
							(mid -0.402042 -0.402042)
							(end -0.3302 -0.4318)
						)
						(arc
							(start 0.3302 -0.4318)
							(mid 0.402042 -0.402042)
							(end 0.4318 -0.3302)
						)
						(arc
							(start 0.4318 0.3302)
							(mid 0.402042 0.402042)
							(end 0.3302 0.4318)
						)
					)
					(width 0)
					(fill yes)
				)
			)
		)
	)
	(footprint ""
		(layer "B.Cu")
		(at 204.763624 -52.924202 -90)
		(property "Reference" "C340"
			(at 0 0 90)
			(layer "B.SilkS")
			(hide yes)
			(effects
				(font
					(size 1.27 1.27)
				)
				(justify mirror)
			)
		)
		(property "Value" "SC1U6D3V1MX-GP"
			(at -1.9177 2.0193 270)
			(unlocked yes)
			(layer "B.Fab")
			(hide yes)
			(effects
				(font
					(size 1.016 1.016)
					(thickness 0.1524)
				)
				(justify mirror)
			)
		)
		(property "Device Type" "C0201H14"
			(at -1.9177 0.4953 270)
			(unlocked yes)
			(layer "B.Fab")
			(hide yes)
			(effects
				(font
					(size 1.016 1.016)
					(thickness 0.1524)
				)
				(justify mirror)
			)
		)
		(duplicate_pad_numbers_are_jumpers no)
		(fp_rect
			(start 0.1524 0.3048)
			(end -0.1524 -0.3048)
			(stroke
				(width 0)
				(type default)
			)
			(fill no)
			(layer "B.CrtYd")
		)
		(fp_poly
			(pts
				(xy 0.2794 0.6477) (xy 0.2794 -0.6477) (xy -0.2794 -0.6477) (xy -0.2794 -0.1905) (xy -0.1524 -0.1905)
				(xy -0.1524 -0.3048) (xy 0.1524 -0.3048) (xy 0.1524 0.3048) (xy -0.1524 0.3048) (xy -0.1524 -0.1778)
				(xy -0.2794 -0.1778) (xy -0.2794 0.6477)
			)
			(stroke
				(width 0)
				(type default)
			)
			(fill no)
			(layer "B.CrtYd")
		)
		(fp_rect
			(start 0.2794 0.6477)
			(end -0.2794 -0.6477)
			(stroke
				(width 0)
				(type default)
			)
			(fill no)
			(layer "B.Fab")
		)
		(pad "1" smd custom
			(at 0 -0.2794 90)
			(size 0.0762 0.0762)
			(layers "B.Cu" "B.Mask" "B.Paste")
			(net "SHELL_PLL_VDD")
			(options
				(clearance outline)
				(anchor circle)
			)
			(primitives
				(gr_poly
					(pts
						(arc
							(start 0.1524 0.127)
							(mid 0.137521 0.162921)
							(end 0.1016 0.1778)
						)
						(arc
							(start -0.1016 0.1778)
							(mid -0.137521 0.162921)
							(end -0.1524 0.127)
						)
						(arc
							(start -0.1524 -0.127)
							(mid -0.137521 -0.162921)
							(end -0.1016 -0.1778)
						)
						(arc
							(start 0.1016 -0.1778)
							(mid 0.137521 -0.162921)
							(end 0.1524 -0.127)
						)
					)
					(width 0)
					(fill yes)
				)
			)
		)
		(pad "2" smd custom
			(at 0 0.2794 90)
			(size 0.0762 0.0762)
			(layers "B.Cu" "B.Mask" "B.Paste")
			(net "GND")
			(options
				(clearance outline)
				(anchor circle)
			)
			(primitives
				(gr_poly
					(pts
						(arc
							(start 0.1524 0.127)
							(mid 0.137521 0.162921)
							(end 0.1016 0.1778)
						)
						(arc
							(start -0.1016 0.1778)
							(mid -0.137521 0.162921)
							(end -0.1524 0.127)
						)
						(arc
							(start -0.1524 -0.127)
							(mid -0.137521 -0.162921)
							(end -0.1016 -0.1778)
						)
						(arc
							(start 0.1016 -0.1778)
							(mid 0.137521 -0.162921)
							(end 0.1524 -0.127)
						)
					)
					(width 0)
					(fill yes)
				)
			)
		)
	)
	(footprint ""
		(layer "B.Cu")
		(at 54.0766 -164.973 90)
		(property "Reference" "C124"
			(at 0 0 90)
			(layer "B.SilkS")
			(hide yes)
			(effects
				(font
					(size 1.27 1.27)
				)
				(justify mirror)
			)
		)
		(property "Value" "SCD1U25V2KX-2-GP"
			(at -1.1811 -2.7051 90)
			(unlocked yes)
			(layer "B.Fab")
			(hide yes)
			(effects
				(font
					(size 1.016 1.016)
					(thickness 0.1524)
				)
				(justify mirror)
			)
		)
		(property "Device Type" "C402H22"
			(at -1.1811 -4.2291 90)
			(unlocked yes)
			(layer "B.Fab")
			(hide yes)
			(effects
				(font
					(size 1.016 1.016)
					(thickness 0.1524)
				)
				(justify mirror)
			)
		)
		(duplicate_pad_numbers_are_jumpers no)
		(fp_rect
			(start 0.4318 0.9525)
			(end -0.4318 -0.9525)
			(stroke
				(width 0)
				(type default)
			)
			(fill no)
			(layer "B.CrtYd")
		)
		(fp_rect
			(start 0.4318 0.9525)
			(end -0.4318 -0.9525)
			(stroke
				(width 0)
				(type default)
			)
			(fill no)
			(layer "B.Fab")
		)
		(pad "1" smd custom
			(at 0 -0.4445 270)
			(size 0.1524 0.1524)
			(layers "B.Cu" "B.Mask" "B.Paste")
			(net "ADC_P0V975")
			(options
				(clearance outline)
				(anchor circle)
			)
			(primitives
				(gr_poly
					(pts
						(arc
							(start 0.3048 0.2032)
							(mid 0.275042 0.275042)
							(end 0.2032 0.3048)
						)
						(arc
							(start -0.2032 0.3048)
							(mid -0.275042 0.275042)
							(end -0.3048 0.2032)
						)
						(arc
							(start -0.3048 -0.2032)
							(mid -0.275042 -0.275042)
							(end -0.2032 -0.3048)
						)
						(arc
							(start 0.2032 -0.3048)
							(mid 0.275042 -0.275042)
							(end 0.3048 -0.2032)
						)
					)
					(width 0)
					(fill yes)
				)
			)
		)
		(pad "2" smd custom
			(at 0 0.4445 270)
			(size 0.1524 0.1524)
			(layers "B.Cu" "B.Mask" "B.Paste")
			(net "GND")
			(options
				(clearance outline)
				(anchor circle)
			)
			(primitives
				(gr_poly
					(pts
						(arc
							(start 0.3048 0.2032)
							(mid 0.275042 0.275042)
							(end 0.2032 0.3048)
						)
						(arc
							(start -0.2032 0.3048)
							(mid -0.275042 0.275042)
							(end -0.3048 0.2032)
						)
						(arc
							(start -0.3048 -0.2032)
							(mid -0.275042 -0.275042)
							(end -0.2032 -0.3048)
						)
						(arc
							(start 0.2032 -0.3048)
							(mid 0.275042 -0.275042)
							(end 0.3048 -0.2032)
						)
					)
					(width 0)
					(fill yes)
				)
			)
		)
	)
	(footprint ""
		(layer "B.Cu")
		(at 36.039298 -143.075914)
		(property "Reference" "C60"
			(at 0 0 0)
			(layer "B.SilkS")
			(hide yes)
			(effects
				(font
					(size 1.27 1.27)
				)
				(justify mirror)
			)
		)
		(property "Value" "SC1U16V3KX-5GP"
			(at 0 -2.8194 0)
			(unlocked yes)
			(layer "B.Fab")
			(hide yes)
			(effects
				(font
					(size 1.016 1.016)
					(thickness 0.1524)
				)
				(justify mirror)
			)
		)
		(property "Device Type" "C603H36"
			(at 0 -4.3434 0)
			(unlocked yes)
			(layer "B.Fab")
			(hide yes)
			(effects
				(font
					(size 1.016 1.016)
					(thickness 0.1524)
				)
				(justify mirror)
			)
		)
		(duplicate_pad_numbers_are_jumpers no)
		(fp_line
			(start -0.508 0)
			(end 0.508 0)
			(stroke
				(width 0.2032)
				(type default)
			)
			(layer "B.SilkS")
		)
		(fp_rect
			(start 0.5842 1.3335)
			(end -0.5842 -1.3335)
			(stroke
				(width 0)
				(type default)
			)
			(fill no)
			(layer "B.CrtYd")
		)
		(fp_rect
			(start 0.5842 1.3335)
			(end -0.5842 -1.3335)
			(stroke
				(width 0)
				(type default)
			)
			(fill no)
			(layer "B.Fab")
		)
		(pad "1" smd custom
			(at 0 -0.762 180)
			(size 0.2159 0.2159)
			(layers "B.Cu" "B.Mask" "B.Paste")
			(net "P1V2_STBY")
			(options
				(clearance outline)
				(anchor circle)
			)
			(primitives
				(gr_poly
					(pts
						(arc
							(start -0.3302 0.4318)
							(mid -0.402042 0.402042)
							(end -0.4318 0.3302)
						)
						(arc
							(start -0.4318 -0.3302)
							(mid -0.402042 -0.402042)
							(end -0.3302 -0.4318)
						)
						(arc
							(start 0.3302 -0.4318)
							(mid 0.402042 -0.402042)
							(end 0.4318 -0.3302)
						)
						(arc
							(start 0.4318 0.3302)
							(mid 0.402042 0.402042)
							(end 0.3302 0.4318)
						)
					)
					(width 0)
					(fill yes)
				)
			)
		)
		(pad "2" smd custom
			(at 0 0.762 180)
			(size 0.2159 0.2159)
			(layers "B.Cu" "B.Mask" "B.Paste")
			(net "GND")
			(options
				(clearance outline)
				(anchor circle)
			)
			(primitives
				(gr_poly
					(pts
						(arc
							(start -0.3302 0.4318)
							(mid -0.402042 0.402042)
							(end -0.4318 0.3302)
						)
						(arc
							(start -0.4318 -0.3302)
							(mid -0.402042 -0.402042)
							(end -0.3302 -0.4318)
						)
						(arc
							(start 0.3302 -0.4318)
							(mid 0.402042 -0.402042)
							(end 0.4318 -0.3302)
						)
						(arc
							(start 0.4318 0.3302)
							(mid 0.402042 0.402042)
							(end 0.3302 0.4318)
						)
					)
					(width 0)
					(fill yes)
				)
			)
		)
	)
	(footprint ""
		(layer "B.Cu")
		(at 193.9671 -63.2206 90)
		(property "Reference" "C403"
			(at 0 0 90)
			(layer "B.SilkS")
			(hide yes)
			(effects
				(font
					(size 1.27 1.27)
				)
				(justify mirror)
			)
		)
		(property "Value" "SCD1U6D3V1KX-GP"
			(at 2.8321 -1.7399 90)
			(unlocked yes)
			(layer "B.Fab")
			(hide yes)
			(effects
				(font
					(size 1.016 1.016)
					(thickness 0.1524)
				)
				(justify mirror)
			)
		)
		(property "Device Type" "C0201H13"
			(at 2.8321 -3.2639 90)
			(unlocked yes)
			(layer "B.Fab")
			(hide yes)
			(effects
				(font
					(size 1.016 1.016)
					(thickness 0.1524)
				)
				(justify mirror)
			)
		)
		(duplicate_pad_numbers_are_jumpers no)
		(fp_rect
			(start 0.2794 0.6477)
			(end -0.2794 -0.6477)
			(stroke
				(width 0)
				(type default)
			)
			(fill no)
			(layer "B.CrtYd")
		)
		(fp_rect
			(start 0.2794 0.6477)
			(end -0.2794 -0.6477)
			(stroke
				(width 0)
				(type default)
			)
			(fill no)
			(layer "B.Fab")
		)
		(pad "1" smd custom
			(at 0 -0.2794 270)
			(size 0.0762 0.0762)
			(layers "B.Cu" "B.Mask" "B.Paste")
			(net "P0V975")
			(options
				(clearance outline)
				(anchor circle)
			)
			(primitives
				(gr_poly
					(pts
						(arc
							(start 0.1524 0.127)
							(mid 0.137521 0.162921)
							(end 0.1016 0.1778)
						)
						(arc
							(start -0.1016 0.1778)
							(mid -0.137521 0.162921)
							(end -0.1524 0.127)
						)
						(arc
							(start -0.1524 -0.127)
							(mid -0.137521 -0.162921)
							(end -0.1016 -0.1778)
						)
						(arc
							(start 0.1016 -0.1778)
							(mid 0.137521 -0.162921)
							(end 0.1524 -0.127)
						)
					)
					(width 0)
					(fill yes)
				)
			)
		)
		(pad "2" smd custom
			(at 0 0.2794 270)
			(size 0.0762 0.0762)
			(layers "B.Cu" "B.Mask" "B.Paste")
			(net "GND")
			(options
				(clearance outline)
				(anchor circle)
			)
			(primitives
				(gr_poly
					(pts
						(arc
							(start 0.1524 0.127)
							(mid 0.137521 0.162921)
							(end 0.1016 0.1778)
						)
						(arc
							(start -0.1016 0.1778)
							(mid -0.137521 0.162921)
							(end -0.1524 0.127)
						)
						(arc
							(start -0.1524 -0.127)
							(mid -0.137521 -0.162921)
							(end -0.1016 -0.1778)
						)
						(arc
							(start 0.1016 -0.1778)
							(mid 0.137521 -0.162921)
							(end 0.1524 -0.127)
						)
					)
					(width 0)
					(fill yes)
				)
			)
		)
	)
	(footprint ""
		(layer "B.Cu")
		(at 96.980756 -159.78632 90)
		(property "Reference" "C8"
			(at 0 0 90)
			(layer "B.SilkS")
			(hide yes)
			(effects
				(font
					(size 1.27 1.27)
				)
				(justify mirror)
			)
		)
		(property "Value" "SC1U16V3KX-5GP"
			(at 0 -2.8194 90)
			(unlocked yes)
			(layer "B.Fab")
			(hide yes)
			(effects
				(font
					(size 1.016 1.016)
					(thickness 0.1524)
				)
				(justify mirror)
			)
		)
		(property "Device Type" "C603H36"
			(at 0 -4.3434 90)
			(unlocked yes)
			(layer "B.Fab")
			(hide yes)
			(effects
				(font
					(size 1.016 1.016)
					(thickness 0.1524)
				)
				(justify mirror)
			)
		)
		(duplicate_pad_numbers_are_jumpers no)
		(fp_line
			(start -0.508 0)
			(end 0.508 0)
			(stroke
				(width 0.2032)
				(type default)
			)
			(layer "B.SilkS")
		)
		(fp_rect
			(start 0.5842 1.3335)
			(end -0.5842 -1.3335)
			(stroke
				(width 0)
				(type default)
			)
			(fill no)
			(layer "B.CrtYd")
		)
		(fp_rect
			(start 0.5842 1.3335)
			(end -0.5842 -1.3335)
			(stroke
				(width 0)
				(type default)
			)
			(fill no)
			(layer "B.Fab")
		)
		(pad "1" smd custom
			(at 0 -0.762 270)
			(size 0.2159 0.2159)
			(layers "B.Cu" "B.Mask" "B.Paste")
			(net "USB_RESET_N")
			(options
				(clearance outline)
				(anchor circle)
			)
			(primitives
				(gr_poly
					(pts
						(arc
							(start -0.3302 0.4318)
							(mid -0.402042 0.402042)
							(end -0.4318 0.3302)
						)
						(arc
							(start -0.4318 -0.3302)
							(mid -0.402042 -0.402042)
							(end -0.3302 -0.4318)
						)
						(arc
							(start 0.3302 -0.4318)
							(mid 0.402042 -0.402042)
							(end 0.4318 -0.3302)
						)
						(arc
							(start 0.4318 0.3302)
							(mid 0.402042 0.402042)
							(end 0.3302 0.4318)
						)
					)
					(width 0)
					(fill yes)
				)
			)
		)
		(pad "2" smd custom
			(at 0 0.762 270)
			(size 0.2159 0.2159)
			(layers "B.Cu" "B.Mask" "B.Paste")
			(net "GND")
			(options
				(clearance outline)
				(anchor circle)
			)
			(primitives
				(gr_poly
					(pts
						(arc
							(start -0.3302 0.4318)
							(mid -0.402042 0.402042)
							(end -0.4318 0.3302)
						)
						(arc
							(start -0.4318 -0.3302)
							(mid -0.402042 -0.402042)
							(end -0.3302 -0.4318)
						)
						(arc
							(start 0.3302 -0.4318)
							(mid 0.402042 -0.402042)
							(end 0.4318 -0.3302)
						)
						(arc
							(start 0.4318 0.3302)
							(mid 0.402042 0.402042)
							(end 0.3302 0.4318)
						)
					)
					(width 0)
					(fill yes)
				)
			)
		)
	)
)
